(kicad_pcb
	(version 20260206)
	(generator "pcbnew")
	(generator_version "10.0")
	(general
		(thickness 1.6)
		(legacy_teardrops no)
	)
	(paper "A4")
	(title_block
		(title "01162023_DA0F0TEBIF0_F0T_Expander_BD_F_brd_V02_OCP.brd")
		(comment 1 "Grand Teton / footprints 4872-4878 of 9728")
	)
	(layers
		(0 "F.Cu" signal "TOP")
		(4 "In1.Cu" signal "GND")
		(6 "In2.Cu" signal "VCC")
		(8 "In3.Cu" signal "VCC1")
		(10 "In4.Cu" signal "GND1")
		(12 "In5.Cu" signal "IN1")
		(14 "In6.Cu" signal "GND2")
		(16 "In7.Cu" signal "IN2")
		(18 "In8.Cu" signal "GND3")
		(20 "In9.Cu" signal "IN3")
		(22 "In10.Cu" signal "GND4")
		(24 "In11.Cu" signal "IN4")
		(26 "In12.Cu" signal "GND5")
		(28 "In13.Cu" signal "IN5")
		(30 "In14.Cu" signal "GND6")
		(32 "In15.Cu" signal "IN6")
		(34 "In16.Cu" signal "GND7")
		(2 "B.Cu" signal "BOTTOM")
		(9 "F.Adhes" user "F.Adhesive")
		(11 "B.Adhes" user "B.Adhesive")
		(13 "F.Paste" user "Package Geometry/Pastemask Top")
		(15 "B.Paste" user "Package Geometry/Pastemask Bottom")
		(5 "F.SilkS" user "Ref Des/Silkscreen Top")
		(7 "B.SilkS" user "Ref Des/Silkscreen Bottom")
		(1 "F.Mask" user "Board Geometry/Soldermask Top")
		(3 "B.Mask" user "Board Geometry/Soldermask Bottom")
		(17 "Dwgs.User" user "User.Drawings")
		(19 "Cmts.User" user "User.Comments")
		(21 "Eco1.User" user "User.Eco1")
		(23 "Eco2.User" user "User.Eco2")
		(25 "Edge.Cuts" user "Board Geometry/Outline")
		(27 "Margin" user)
		(31 "F.CrtYd" user "Package Geometry/Place Bound Top")
		(29 "B.CrtYd" user "Package Geometry/Place Bound Bottom")
		(35 "F.Fab" user "Ref Des/Assembly Top")
		(33 "B.Fab" user "Ref Des/Assembly Bottom")
	)
	(footprint ""
		(layer "F.Cu")
		(at 234.541822 -27.006296 -90)
		(property "Reference" "PR7116"
			(at 0 0 270)
			(layer "F.SilkS")
			(hide yes)
			(effects
				(font
					(size 1.27 1.27)
				)
			)
		)
		(property "Value" ""
			(at 0 0 270)
			(layer "F.Fab")
			(effects
				(font
					(size 1.27 1.27)
				)
			)
		)
		(duplicate_pad_numbers_are_jumpers no)
		(fp_line
			(start -0.7874 0.4064)
			(end -0.7874 -0.4064)
			(stroke
				(width 0.1524)
				(type default)
			)
			(layer "F.SilkS")
		)
		(fp_line
			(start 0.7874 0.4064)
			(end -0.7874 0.4064)
			(stroke
				(width 0.1524)
				(type default)
			)
			(layer "F.SilkS")
		)
		(fp_line
			(start -0.7874 -0.4064)
			(end 0.7874 -0.4064)
			(stroke
				(width 0.1524)
				(type default)
			)
			(layer "F.SilkS")
		)
		(fp_line
			(start 0.7874 -0.4064)
			(end 0.7874 0.4064)
			(stroke
				(width 0.1524)
				(type default)
			)
			(layer "F.SilkS")
		)
		(fp_line
			(start -0.67945 0.3048)
			(end -0.67945 -0.305054)
			(stroke
				(width 0.1)
				(type default)
			)
			(layer "F.Fab")
		)
		(fp_line
			(start -0.12065 0.3048)
			(end -0.67945 0.3048)
			(stroke
				(width 0.1)
				(type default)
			)
			(layer "F.Fab")
		)
		(fp_line
			(start 0.120396 0.3048)
			(end 0.120396 0.2794)
			(stroke
				(width 0.1)
				(type default)
			)
			(layer "F.Fab")
		)
		(fp_line
			(start 0.67945 0.3048)
			(end 0.120396 0.3048)
			(stroke
				(width 0.1)
				(type default)
			)
			(layer "F.Fab")
		)
		(fp_line
			(start -0.12065 0.2794)
			(end -0.12065 0.3048)
			(stroke
				(width 0.1)
				(type default)
			)
			(layer "F.Fab")
		)
		(fp_line
			(start 0.120396 0.2794)
			(end -0.12065 0.2794)
			(stroke
				(width 0.1)
				(type default)
			)
			(layer "F.Fab")
		)
		(fp_line
			(start -0.12065 -0.2794)
			(end 0.12065 -0.2794)
			(stroke
				(width 0.1)
				(type default)
			)
			(layer "F.Fab")
		)
		(fp_line
			(start 0.12065 -0.2794)
			(end 0.12065 -0.3048)
			(stroke
				(width 0.1)
				(type default)
			)
			(layer "F.Fab")
		)
		(fp_line
			(start 0.12065 -0.3048)
			(end 0.67945 -0.3048)
			(stroke
				(width 0.1)
				(type default)
			)
			(layer "F.Fab")
		)
		(fp_line
			(start 0.67945 -0.3048)
			(end 0.67945 0.3048)
			(stroke
				(width 0.1)
				(type default)
			)
			(layer "F.Fab")
		)
		(fp_line
			(start -0.67945 -0.305054)
			(end -0.12065 -0.305054)
			(stroke
				(width 0.1)
				(type default)
			)
			(layer "F.Fab")
		)
		(fp_line
			(start -0.12065 -0.305054)
			(end -0.12065 -0.2794)
			(stroke
				(width 0.1)
				(type default)
			)
			(layer "F.Fab")
		)
		(pad "1" smd circle
			(at -0.40005 0 270)
			(size 0 0)
			(layers "F.Cu" "F.Mask" "F.Paste")
			(net "P3V3_SSD8_CO_ILIMIT")
		)
		(pad "2" smd circle
			(at 0.40005 0 270)
			(size 0 0)
			(layers "F.Cu" "F.Mask" "F.Paste")
			(net "GND")
		)
	)
	(footprint ""
		(layer "F.Cu")
		(at 115.356386 -89.384378 180)
		(property "Reference" "R1149"
			(at 0 0 180)
			(layer "F.SilkS")
			(hide yes)
			(effects
				(font
					(size 1.27 1.27)
				)
			)
		)
		(property "Value" ""
			(at 0 0 180)
			(layer "F.Fab")
			(effects
				(font
					(size 1.27 1.27)
				)
			)
		)
		(duplicate_pad_numbers_are_jumpers no)
		(fp_line
			(start 0.7874 0.4064)
			(end -0.7874 0.4064)
			(stroke
				(width 0.1524)
				(type default)
			)
			(layer "F.SilkS")
		)
		(fp_line
			(start 0.67945 0.3048)
			(end 0.120396 0.3048)
			(stroke
				(width 0.1)
				(type default)
			)
			(layer "F.Fab")
		)
		(fp_line
			(start 0.67945 -0.3048)
			(end 0.67945 0.3048)
			(stroke
				(width 0.1)
				(type default)
			)
			(layer "F.Fab")
		)
		(fp_line
			(start 0.12065 -0.2794)
			(end 0.12065 -0.3048)
			(stroke
				(width 0.1)
				(type default)
			)
			(layer "F.Fab")
		)
		(fp_line
			(start 0.12065 -0.3048)
			(end 0.67945 -0.3048)
			(stroke
				(width 0.1)
				(type default)
			)
			(layer "F.Fab")
		)
		(fp_line
			(start 0.120396 0.3048)
			(end 0.120396 0.2794)
			(stroke
				(width 0.1)
				(type default)
			)
			(layer "F.Fab")
		)
		(fp_line
			(start 0.120396 0.2794)
			(end -0.12065 0.2794)
			(stroke
				(width 0.1)
				(type default)
			)
			(layer "F.Fab")
		)
		(fp_line
			(start -0.12065 0.3048)
			(end -0.67945 0.3048)
			(stroke
				(width 0.1)
				(type default)
			)
			(layer "F.Fab")
		)
		(fp_line
			(start -0.12065 0.2794)
			(end -0.12065 0.3048)
			(stroke
				(width 0.1)
				(type default)
			)
			(layer "F.Fab")
		)
		(fp_line
			(start -0.12065 -0.2794)
			(end 0.12065 -0.2794)
			(stroke
				(width 0.1)
				(type default)
			)
			(layer "F.Fab")
		)
		(fp_line
			(start -0.12065 -0.305054)
			(end -0.12065 -0.2794)
			(stroke
				(width 0.1)
				(type default)
			)
			(layer "F.Fab")
		)
		(fp_line
			(start -0.67945 0.3048)
			(end -0.67945 -0.305054)
			(stroke
				(width 0.1)
				(type default)
			)
			(layer "F.Fab")
		)
		(fp_line
			(start -0.67945 -0.305054)
			(end -0.12065 -0.305054)
			(stroke
				(width 0.1)
				(type default)
			)
			(layer "F.Fab")
		)
		(pad "1" smd circle
			(at -0.40005 0 180)
			(size 0 0)
			(layers "F.Cu" "F.Mask" "F.Paste")
			(net "CLK_100M_DB800ZL_SSD6_R_DN")
		)
		(pad "2" smd circle
			(at 0.40005 0 180)
			(size 0 0)
			(layers "F.Cu" "F.Mask" "F.Paste")
			(net "CLK_100M_DB800ZL_SSD6_DN")
		)
	)
	(footprint ""
		(layer "F.Cu")
		(at 249.204734 -215.543638 180)
		(property "Reference" "C2851"
			(at 0 0 180)
			(layer "F.SilkS")
			(hide yes)
			(effects
				(font
					(size 1.27 1.27)
				)
			)
		)
		(property "Value" ""
			(at 0 0 180)
			(layer "F.Fab")
			(effects
				(font
					(size 1.27 1.27)
				)
			)
		)
		(duplicate_pad_numbers_are_jumpers no)
		(fp_line
			(start 0.7874 0.4064)
			(end -0.7874 0.4064)
			(stroke
				(width 0.1524)
				(type default)
			)
			(layer "F.SilkS")
		)
		(fp_line
			(start 0.7874 -0.4064)
			(end 0.7874 0.4064)
			(stroke
				(width 0.1524)
				(type default)
			)
			(layer "F.SilkS")
		)
		(fp_line
			(start -0.7874 0.4064)
			(end -0.7874 -0.4064)
			(stroke
				(width 0.1524)
				(type default)
			)
			(layer "F.SilkS")
		)
		(fp_line
			(start -0.7874 -0.4064)
			(end 0.7874 -0.4064)
			(stroke
				(width 0.1524)
				(type default)
			)
			(layer "F.SilkS")
		)
		(fp_line
			(start 0.67945 0.3048)
			(end 0.120396 0.3048)
			(stroke
				(width 0.1)
				(type default)
			)
			(layer "F.Fab")
		)
		(fp_line
			(start 0.67945 -0.3048)
			(end 0.67945 0.3048)
			(stroke
				(width 0.1)
				(type default)
			)
			(layer "F.Fab")
		)
		(fp_line
			(start 0.12065 -0.2794)
			(end 0.12065 -0.3048)
			(stroke
				(width 0.1)
				(type default)
			)
			(layer "F.Fab")
		)
		(fp_line
			(start 0.12065 -0.3048)
			(end 0.67945 -0.3048)
			(stroke
				(width 0.1)
				(type default)
			)
			(layer "F.Fab")
		)
		(fp_line
			(start 0.120396 0.3048)
			(end 0.120396 0.2794)
			(stroke
				(width 0.1)
				(type default)
			)
			(layer "F.Fab")
		)
		(fp_line
			(start 0.120396 0.2794)
			(end -0.12065 0.2794)
			(stroke
				(width 0.1)
				(type default)
			)
			(layer "F.Fab")
		)
		(fp_line
			(start -0.12065 0.3048)
			(end -0.67945 0.3048)
			(stroke
				(width 0.1)
				(type default)
			)
			(layer "F.Fab")
		)
		(fp_line
			(start -0.12065 0.2794)
			(end -0.12065 0.3048)
			(stroke
				(width 0.1)
				(type default)
			)
			(layer "F.Fab")
		)
		(fp_line
			(start -0.12065 -0.2794)
			(end 0.12065 -0.2794)
			(stroke
				(width 0.1)
				(type default)
			)
			(layer "F.Fab")
		)
		(fp_line
			(start -0.12065 -0.305054)
			(end -0.12065 -0.2794)
			(stroke
				(width 0.1)
				(type default)
			)
			(layer "F.Fab")
		)
		(fp_line
			(start -0.67945 0.3048)
			(end -0.67945 -0.305054)
			(stroke
				(width 0.1)
				(type default)
			)
			(layer "F.Fab")
		)
		(fp_line
			(start -0.67945 -0.305054)
			(end -0.12065 -0.305054)
			(stroke
				(width 0.1)
				(type default)
			)
			(layer "F.Fab")
		)
		(pad "1" smd circle
			(at -0.40005 0 180)
			(size 0 0)
			(layers "F.Cu" "F.Mask" "F.Paste")
			(net "P1V2_AUX")
		)
		(pad "2" smd circle
			(at 0.40005 0 180)
			(size 0 0)
			(layers "F.Cu" "F.Mask" "F.Paste")
			(net "GND")
		)
	)
	(footprint ""
		(layer "F.Cu")
		(at 239.703864 -218.29776 90)
		(property "Reference" "C3615"
			(at 0 0 90)
			(layer "F.SilkS")
			(hide yes)
			(effects
				(font
					(size 1.27 1.27)
				)
			)
		)
		(property "Value" ""
			(at 0 0 90)
			(layer "F.Fab")
			(effects
				(font
					(size 1.27 1.27)
				)
			)
		)
		(duplicate_pad_numbers_are_jumpers no)
		(fp_line
			(start 0.69215 -0.2921)
			(end 0.69215 0.2921)
			(stroke
				(width 0.1524)
				(type default)
			)
			(layer "F.SilkS")
		)
		(fp_line
			(start -0.69215 -0.2921)
			(end 0.69215 -0.2921)
			(stroke
				(width 0.1524)
				(type default)
			)
			(layer "F.SilkS")
		)
		(fp_line
			(start 0.69215 0.2921)
			(end -0.69215 0.2921)
			(stroke
				(width 0.1524)
				(type default)
			)
			(layer "F.SilkS")
		)
		(fp_line
			(start -0.69215 0.2921)
			(end -0.69215 -0.2921)
			(stroke
				(width 0.1524)
				(type default)
			)
			(layer "F.SilkS")
		)
		(fp_line
			(start 0.51435 -0.2794)
			(end 0.51435 0.2794)
			(stroke
				(width 0.1)
				(type default)
			)
			(layer "F.Fab")
		)
		(fp_line
			(start -0.51435 -0.2794)
			(end 0.51435 -0.2794)
			(stroke
				(width 0.1)
				(type default)
			)
			(layer "F.Fab")
		)
		(fp_line
			(start 0.51435 0.2794)
			(end -0.51435 0.2794)
			(stroke
				(width 0.1)
				(type default)
			)
			(layer "F.Fab")
		)
		(fp_line
			(start -0.51435 0.2794)
			(end -0.51435 -0.2794)
			(stroke
				(width 0.1)
				(type default)
			)
			(layer "F.Fab")
		)
		(pad "1" smd circle
			(at -0.40005 0 90)
			(size 0 0)
			(layers "F.Cu" "F.Mask" "F.Paste")
			(net "BIC_ADCVREFP0")
		)
		(pad "2" smd circle
			(at 0.40005 0 90)
			(size 0 0)
			(layers "F.Cu" "F.Mask" "F.Paste")
			(net "BIC_ADCVREFN0")
		)
		(zone
			(layer "F.Cu")
			(hatch none 0.5)
			(connect_pads
				(clearance 0)
			)
			(min_thickness 0.25)
			(keepout
				(tracks not_allowed)
				(vias allowed)
				(pads allowed)
				(copperpour not_allowed)
				(footprints allowed)
			)
			(placement
				(enabled no)
				(sheetname "")
			)
			(fill
				(thermal_gap 0.5)
				(thermal_bridge_width 0.5)
				(island_removal_mode 0)
			)
			(polygon
				(pts
					(xy 239.791494 -218.10726) (xy 239.84966 -218.1987) (xy 239.84966 -218.39809) (xy 239.791494 -218.48826)
					(xy 239.616234 -218.48826) (xy 239.557814 -218.39809) (xy 239.557814 -218.1987) (xy 239.61598 -218.10726)
				)
			)
		)
	)
	(footprint ""
		(layer "F.Cu")
		(at 170.975274 -64.102234 180)
		(property "Reference" "PR7073"
			(at 0 0 180)
			(layer "F.SilkS")
			(hide yes)
			(effects
				(font
					(size 1.27 1.27)
				)
			)
		)
		(property "Value" ""
			(at 0 0 180)
			(layer "F.Fab")
			(effects
				(font
					(size 1.27 1.27)
				)
			)
		)
		(duplicate_pad_numbers_are_jumpers no)
		(fp_line
			(start 0.7874 0.4064)
			(end -0.7874 0.4064)
			(stroke
				(width 0.1524)
				(type default)
			)
			(layer "F.SilkS")
		)
		(fp_line
			(start 0.7874 -0.4064)
			(end 0.7874 0.4064)
			(stroke
				(width 0.1524)
				(type default)
			)
			(layer "F.SilkS")
		)
		(fp_line
			(start -0.7874 0.4064)
			(end -0.7874 -0.4064)
			(stroke
				(width 0.1524)
				(type default)
			)
			(layer "F.SilkS")
		)
		(fp_line
			(start -0.7874 -0.4064)
			(end 0.7874 -0.4064)
			(stroke
				(width 0.1524)
				(type default)
			)
			(layer "F.SilkS")
		)
		(fp_line
			(start 0.67945 0.3048)
			(end 0.120396 0.3048)
			(stroke
				(width 0.1)
				(type default)
			)
			(layer "F.Fab")
		)
		(fp_line
			(start 0.67945 -0.3048)
			(end 0.67945 0.3048)
			(stroke
				(width 0.1)
				(type default)
			)
			(layer "F.Fab")
		)
		(fp_line
			(start 0.12065 -0.2794)
			(end 0.12065 -0.3048)
			(stroke
				(width 0.1)
				(type default)
			)
			(layer "F.Fab")
		)
		(fp_line
			(start 0.12065 -0.3048)
			(end 0.67945 -0.3048)
			(stroke
				(width 0.1)
				(type default)
			)
			(layer "F.Fab")
		)
		(fp_line
			(start 0.120396 0.3048)
			(end 0.120396 0.2794)
			(stroke
				(width 0.1)
				(type default)
			)
			(layer "F.Fab")
		)
		(fp_line
			(start 0.120396 0.2794)
			(end -0.12065 0.2794)
			(stroke
				(width 0.1)
				(type default)
			)
			(layer "F.Fab")
		)
		(fp_line
			(start -0.12065 0.3048)
			(end -0.67945 0.3048)
			(stroke
				(width 0.1)
				(type default)
			)
			(layer "F.Fab")
		)
		(fp_line
			(start -0.12065 0.2794)
			(end -0.12065 0.3048)
			(stroke
				(width 0.1)
				(type default)
			)
			(layer "F.Fab")
		)
		(fp_line
			(start -0.12065 -0.2794)
			(end 0.12065 -0.2794)
			(stroke
				(width 0.1)
				(type default)
			)
			(layer "F.Fab")
		)
		(fp_line
			(start -0.12065 -0.305054)
			(end -0.12065 -0.2794)
			(stroke
				(width 0.1)
				(type default)
			)
			(layer "F.Fab")
		)
		(fp_line
			(start -0.67945 0.3048)
			(end -0.67945 -0.305054)
			(stroke
				(width 0.1)
				(type default)
			)
			(layer "F.Fab")
		)
		(fp_line
			(start -0.67945 -0.305054)
			(end -0.12065 -0.305054)
			(stroke
				(width 0.1)
				(type default)
			)
			(layer "F.Fab")
		)
		(pad "1" smd circle
			(at -0.40005 0 180)
			(size 0 0)
			(layers "F.Cu" "F.Mask" "F.Paste")
			(net "P12V_SSD6_PG_G1")
		)
		(pad "2" smd circle
			(at 0.40005 0 180)
			(size 0 0)
			(layers "F.Cu" "F.Mask" "F.Paste")
			(net "GND")
		)
	)
	(footprint ""
		(layer "F.Cu")
		(at 147.001992 -32.849312 90)
		(property "Reference" "R5666"
			(at 0 0 90)
			(layer "F.SilkS")
			(hide yes)
			(effects
				(font
					(size 1.27 1.27)
				)
			)
		)
		(property "Value" ""
			(at 0 0 90)
			(layer "F.Fab")
			(effects
				(font
					(size 1.27 1.27)
				)
			)
		)
		(duplicate_pad_numbers_are_jumpers no)
		(fp_line
			(start 0.7874 -0.4064)
			(end 0.7874 0.4064)
			(stroke
				(width 0.1524)
				(type default)
			)
			(layer "F.SilkS")
		)
		(fp_line
			(start -0.7874 -0.4064)
			(end 0.7874 -0.4064)
			(stroke
				(width 0.1524)
				(type default)
			)
			(layer "F.SilkS")
		)
		(fp_line
			(start 0.7874 0.4064)
			(end -0.7874 0.4064)
			(stroke
				(width 0.1524)
				(type default)
			)
			(layer "F.SilkS")
		)
		(fp_line
			(start -0.7874 0.4064)
			(end -0.7874 -0.4064)
			(stroke
				(width 0.1524)
				(type default)
			)
			(layer "F.SilkS")
		)
		(fp_line
			(start -0.12065 -0.305054)
			(end -0.12065 -0.2794)
			(stroke
				(width 0.1)
				(type default)
			)
			(layer "F.Fab")
		)
		(fp_line
			(start -0.67945 -0.305054)
			(end -0.12065 -0.305054)
			(stroke
				(width 0.1)
				(type default)
			)
			(layer "F.Fab")
		)
		(fp_line
			(start 0.67945 -0.3048)
			(end 0.67945 0.3048)
			(stroke
				(width 0.1)
				(type default)
			)
			(layer "F.Fab")
		)
		(fp_line
			(start 0.12065 -0.3048)
			(end 0.67945 -0.3048)
			(stroke
				(width 0.1)
				(type default)
			)
			(layer "F.Fab")
		)
		(fp_line
			(start 0.12065 -0.2794)
			(end 0.12065 -0.3048)
			(stroke
				(width 0.1)
				(type default)
			)
			(layer "F.Fab")
		)
		(fp_line
			(start -0.12065 -0.2794)
			(end 0.12065 -0.2794)
			(stroke
				(width 0.1)
				(type default)
			)
			(layer "F.Fab")
		)
		(fp_line
			(start 0.120396 0.2794)
			(end -0.12065 0.2794)
			(stroke
				(width 0.1)
				(type default)
			)
			(layer "F.Fab")
		)
		(fp_line
			(start -0.12065 0.2794)
			(end -0.12065 0.3048)
			(stroke
				(width 0.1)
				(type default)
			)
			(layer "F.Fab")
		)
		(fp_line
			(start 0.67945 0.3048)
			(end 0.120396 0.3048)
			(stroke
				(width 0.1)
				(type default)
			)
			(layer "F.Fab")
		)
		(fp_line
			(start 0.120396 0.3048)
			(end 0.120396 0.2794)
			(stroke
				(width 0.1)
				(type default)
			)
			(layer "F.Fab")
		)
		(fp_line
			(start -0.12065 0.3048)
			(end -0.67945 0.3048)
			(stroke
				(width 0.1)
				(type default)
			)
			(layer "F.Fab")
		)
		(fp_line
			(start -0.67945 0.3048)
			(end -0.67945 -0.305054)
			(stroke
				(width 0.1)
				(type default)
			)
			(layer "F.Fab")
		)
		(pad "1" smd circle
			(at -0.40005 0 90)
			(size 0 0)
			(layers "F.Cu" "F.Mask" "F.Paste")
			(net "RST_SMB_SSD5_ISO_R_N")
		)
		(pad "2" smd circle
			(at 0.40005 0 90)
			(size 0 0)
			(layers "F.Cu" "F.Mask" "F.Paste")
			(net "RST_SMB_SSD5_ISO_N")
		)
	)
	(footprint ""
		(layer "F.Cu")
		(at 384.51282 -350.098614 90)
		(property "Reference" "C791"
			(at 0 0 90)
			(layer "F.SilkS")
			(hide yes)
			(effects
				(font
					(size 1.27 1.27)
				)
			)
		)
		(property "Value" ""
			(at 0 0 90)
			(layer "F.Fab")
			(effects
				(font
					(size 1.27 1.27)
				)
			)
		)
		(duplicate_pad_numbers_are_jumpers no)
		(fp_line
			(start 0.299974 -0.150114)
			(end 0.299974 0.150114)
			(stroke
				(width 0.1)
				(type default)
			)
			(layer "F.Fab")
		)
		(fp_line
			(start -0.299974 -0.150114)
			(end 0.299974 -0.150114)
			(stroke
				(width 0.1)
				(type default)
			)
			(layer "F.Fab")
		)
		(fp_line
			(start 0.299974 0.150114)
			(end -0.299974 0.150114)
			(stroke
				(width 0.1)
				(type default)
			)
			(layer "F.Fab")
		)
		(fp_line
			(start -0.299974 0.150114)
			(end -0.299974 -0.150114)
			(stroke
				(width 0.1)
				(type default)
			)
			(layer "F.Fab")
		)
		(pad "1" smd rect
			(at -0.2667 0 90)
			(size 0.3048 0.381)
			(layers "F.Cu" "F.Mask" "F.Paste")
			(net "P5E_PEX3_STN6_TX_DN<97>")
		)
		(pad "2" smd rect
			(at 0.2667 0 90)
			(size 0.3048 0.381)
			(layers "F.Cu" "F.Mask" "F.Paste")
			(net "P5E_PEX3_STN6_TX_C_DN<97>")
		)
	)
)
